#ISCELL
  mstr_misc dns *
  *
#ISCELL
  mstr_symbols cad_note *
  *
#ISCELL
  mstr_symbols design_note *
  *
#ISCELL
  mstr_symbols intel_corp_bpage *
  *
#CELL
  mstr_conn conn76_h22707001 *
  page181_i111
#ISCELL
  mstr_symbols gnd *
  page181_i112
#ISCELL
  mstr_standard tap *
  page181_i113
#ISCELL
  mstr_standard tap *
  page181_i114
#ISCELL
  mstr_standard tap *
  page181_i115
#ISCELL
  mstr_standard tap *
  page181_i116
#ISCELL
  mstr_standard tap *
  page181_i117
#ISCELL
  mstr_standard tap *
  page181_i118
#ISCELL
  mstr_standard tap *
  page181_i119
#ISCELL
  mstr_standard tap *
  page181_i120
#ISCELL
  mstr_standard tap *
  page181_i121
#ISCELL
  mstr_standard tap *
  page181_i122
#ISCELL
  mstr_standard tap *
  page181_i123
#ISCELL
  mstr_standard tap *
  page181_i124
#ISCELL
  mstr_standard tap *
  page181_i125
#ISCELL
  mstr_standard tap *
  page181_i126
#ISCELL
  mstr_standard tap *
  page181_i127
#ISCELL
  mstr_standard tap *
  page181_i128
#ISCELL
  mstr_standard tap *
  page181_i129
#ISCELL
  mstr_standard tap *
  page181_i130
#ISCELL
  mstr_standard tap *
  page181_i131
#ISCELL
  mstr_standard tap *
  page181_i132
#ISCELL
  mstr_standard offpage *
  page181_i133
#ISCELL
  mstr_standard offpage *
  page181_i134
#ISCELL
  mstr_standard offpage *
  page181_i138
#ISCELL
  mstr_standard offpage *
  page181_i139
#ISCELL
  mstr_standard offpage *
  page181_i140
#ISCELL
  mstr_standard offpage *
  page181_i141
#ISCELL
  mstr_standard offpage *
  page181_i142
#ISCELL
  mstr_standard offpage *
  page181_i143
#ISCELL
  mstr_standard offpage *
  page181_i144
#ISCELL
  mstr_standard offpage *
  page181_i145
#ISCELL
  mstr_standard offpage *
  page181_i146
#ISCELL
  mstr_standard offpage *
  page181_i152
#ISCELL
  mstr_standard offpage *
  page181_i157
#ISCELL
  mstr_standard offpage *
  page181_i158
#ISCELL
  mstr_standard offpage *
  page181_i159
#CELL
  mstr_discrete cap *
  page181_i160
#CELL
  mstr_discrete cap *
  page181_i161
#CELL
  mstr_discrete cap *
  page181_i162
#CELL
  mstr_discrete cap *
  page181_i163
#CELL
  mstr_discrete cap *
  page181_i164
#CELL
  mstr_discrete cap *
  page181_i165
#CELL
  mstr_discrete cap *
  page181_i166
#CELL
  mstr_discrete cap *
  page181_i167
#CELL
  mstr_discrete cap *
  page181_i168
#CELL
  mstr_discrete cap *
  page181_i169
#CELL
  mstr_discrete cap *
  page181_i170
#CELL
  mstr_discrete cap *
  page181_i171
#CELL
  mstr_discrete cap *
  page181_i172
#CELL
  mstr_discrete cap *
  page181_i173
#CELL
  mstr_discrete cap *
  page181_i174
#CELL
  mstr_discrete cap *
  page181_i175
#ISCELL
  mstr_symbols p12v_psu *
  page181_i176
#CELL
  mstr_discrete res *
  page181_i177
#CELL
  mstr_discrete diode *
  page181_i178
#ISCELL
  mstr_standard offpage *
  page181_i179
#CELL
  mstr_discrete diode *
  page181_i180
#CELL
  mstr_discrete npn *
  page181_i181
#ISCELL
  mstr_symbols gnd *
  page181_i182
#CELL
  mstr_discrete res *
  page181_i183
#ISCELL
  mstr_symbols p12v_psu *
  page181_i184
#CELL
  mstr_discrete res *
  page181_i185
#ISCELL
  mstr_symbols gnd *
  page181_i186
#ISCELL
  mstr_standard offpage *
  page181_i187
#CELL
  mstr_conn conn8_h62179001 *
  page181_i189
#ISCELL
  mstr_symbols gnd *
  page181_i191
#ISCELL
  mstr_standard offpage *
  page181_i192
#ISCELL
  mstr_standard offpage *
  page181_i193
#ISCELL
  mstr_standard offpage *
  page181_i194
#ISCELL
  mstr_standard offpage *
  page181_i195
#ISCELL
  mstr_symbols p3v3_stby *
  page181_i198
#CELL
  mstr_discrete res *
  page181_i199
#CELL
  mstr_discrete res *
  page181_i200
#CELL
  mstr_discrete res *
  page181_i201
#ISCELL
  mstr_standard offpage *
  page181_i202
#ISCELL
  mstr_standard offpage *
  page181_i203
#ISCELL
  mstr_standard offpage *
  page181_i204
#CELL
  mstr_discrete res *
  page181_i218
#ISCELL
  mstr_standard offpage *
  page181_i221
#ISCELL
  mstr_standard offpage *
  page181_i222
#ISCELL
  mstr_standard offpage *
  page181_i223
#CELL
  mstr_discrete cap *
  page181_i224
#ISCELL
  mstr_symbols gnd *
  page181_i225
#ISCELL
  mstr_symbols p3v3_stby *
  page181_i227
#ISCELL
  mstr_standard offpage *
  page181_i239
#ISCELL
  mstr_standard offpage *
  page181_i241
#CELL
  mstr_ttl ttl08 *
  page181_i243
#ISCELL
  mstr_standard offpage *
  page181_i244
#ISCELL
  mstr_standard offpage *
  page181_i245
#ISCELL
  mstr_standard offpage *
  page181_i246
#ISCELL
  mstr_symbols gnd *
  page181_i248
#ISCELL
  mstr_standard offpage *
  page181_i250
#ISCELL
  mstr_symbols p3v3_stby *
  page181_i251
#ISCELL
  mstr_symbols gnd *
  page181_i252
#CELL
  dev_discrete cap_a *
  page181_i253
#CELL
  mstr_discrete res *
  page181_i254
#CELL
  mstr_discrete res *
  page181_i255
#CELL
  mstr_discrete res *
  page181_i256
#ISCELL
  mstr_standard offpage *
  page181_i257
#ISCELL
  mstr_standard offpage *
  page181_i258
#ISCELL
  mstr_standard offpage *
  page181_i259
#CELL
  mstr_discrete res *
  page181_i261
#ISCELL
  mstr_standard offpage *
  page181_i262
#ISCELL
  mstr_standard offpage *
  page181_i263
#ISCELL
  mstr_standard offpage *
  page181_i264
#ISCELL
  mstr_standard offpage *
  page181_i265
#ISCELL
  mstr_standard offpage *
  page181_i266
#ISCELL
  mstr_standard offpage *
  page181_i267
#CELL
  mstr_discrete res *
  page181_i268
#ISCELL
  mstr_standard offpage *
  page181_i269
#ISCELL
  mstr_standard offpage *
  page181_i272
#ISCELL
  mstr_standard offpage *
  page181_i273
#ISCELL
  mstr_standard offpage *
  page181_i274
#ISCELL
  mstr_standard offpage *
  page181_i275
#CELL
  mstr_discrete res *
  page181_i278
#CELL
  mstr_discrete res *
  page181_i279
#CELL
  mstr_discrete res *
  page181_i280
#CELL
  mstr_discrete res *
  page181_i281
#CELL
  mstr_discrete res *
  page181_i282
#ISCELL
  mstr_symbols gnd *
  page181_i45
#ISCELL
  mstr_standard tap *
  page181_i47
#ISCELL
  mstr_standard tap *
  page181_i48
#ISCELL
  mstr_standard tap *
  page181_i49
#ISCELL
  mstr_standard tap *
  page181_i50
#ISCELL
  mstr_standard tap *
  page181_i53
#ISCELL
  mstr_standard tap *
  page181_i54
#ISCELL
  mstr_standard tap *
  page181_i57
#ISCELL
  mstr_standard tap *
  page181_i58
#ISCELL
  mstr_standard tap *
  page181_i67
#ISCELL
  mstr_standard tap *
  page181_i68
#ISCELL
  mstr_standard tap *
  page181_i69
#ISCELL
  mstr_standard tap *
  page181_i70
